# SCM (Grand Teton) — schematic netlist excerpt (pin names and nets, part order shuffled) for the footprints in the layout excerpt that follows; sources: Cadence DE-HDL packaged netlist, KiCad conversion of 12092022_DA0F0TMDCD0_F0T_Management_Board_D_brd_V3_OCP.brd

R182  Q_RES  0 5% CHIP  pkg 0402LF  page 25 : A = GND ; B = FLASH_LATCH_D
R526  Q_RES  33.2 1% EMPTY  pkg 0402LF  page 35 : A = BMC_CPLD_GPIO_7_R2 ; B = BMC_CPLD_GPIO_7

(kicad_pcb
	(version 20260206)
	(generator "pcbnew")
	(generator_version "10.0")
	(general
		(thickness 1.6)
		(legacy_teardrops no)
	)
	(paper "A4")
	(title_block
		(title "12092022_DA0F0TMDCD0_F0T_Management_Board_D_brd_V3_OCP.brd")
		(comment 1 "Grand Teton / footprints 297-298 of 1440")
	)
	(layers
		(0 "F.Cu" signal "TOP")
		(4 "In1.Cu" signal "GND")
		(6 "In2.Cu" signal "IN1")
		(8 "In3.Cu" signal "GND1")
		(10 "In4.Cu" signal "IN2")
		(12 "In5.Cu" signal "VCC")
		(14 "In6.Cu" signal "VCC1")
		(16 "In7.Cu" signal "IN3")
		(18 "In8.Cu" signal "GND2")
		(20 "In9.Cu" signal "IN4")
		(22 "In10.Cu" signal "GND3")
		(2 "B.Cu" signal "BOTTOM")
		(9 "F.Adhes" user "F.Adhesive")
		(11 "B.Adhes" user "B.Adhesive")
		(13 "F.Paste" user "Package Geometry/Pastemask Top")
		(15 "B.Paste" user "Package Geometry/Pastemask Bottom")
		(5 "F.SilkS" user "Ref Des/Silkscreen Top")
		(7 "B.SilkS" user "Ref Des/Silkscreen Bottom")
		(1 "F.Mask" user "Board Geometry/Soldermask Top")
		(3 "B.Mask" user "Board Geometry/Soldermask Bottom")
		(17 "Dwgs.User" user "User.Drawings")
		(19 "Cmts.User" user "User.Comments")
		(21 "Eco1.User" user "User.Eco1")
		(23 "Eco2.User" user "User.Eco2")
		(25 "Edge.Cuts" user "Board Geometry/Outline")
		(27 "Margin" user)
		(31 "F.CrtYd" user "Package Geometry/Place Bound Top")
		(29 "B.CrtYd" user "Package Geometry/Place Bound Bottom")
		(35 "F.Fab" user "Ref Des/Assembly Top")
		(33 "B.Fab" user "Ref Des/Assembly Bottom")
	)
	(footprint ""
		(layer "F.Cu")
		(at 12.319 -88.392 180)
		(property "Reference" "R526"
			(at 0 0 180)
			(layer "F.SilkS")
			(hide yes)
			(effects
				(font
					(size 1.27 1.27)
				)
			)
		)
		(property "Value" ""
			(at 0 0 180)
			(layer "F.Fab")
			(effects
				(font
					(size 1.27 1.27)
				)
			)
		)
		(duplicate_pad_numbers_are_jumpers no)
		(fp_line
			(start 0.7874 0.4064)
			(end -0.7874 0.4064)
			(stroke
				(width 0.1524)
				(type default)
			)
			(layer "F.SilkS")
		)
		(fp_line
			(start 0.7874 -0.4064)
			(end 0.7874 0.4064)
			(stroke
				(width 0.1524)
				(type default)
			)
			(layer "F.SilkS")
		)
		(fp_line
			(start -0.7874 0.4064)
			(end -0.7874 -0.4064)
			(stroke
				(width 0.1524)
				(type default)
			)
			(layer "F.SilkS")
		)
		(fp_line
			(start -0.7874 -0.4064)
			(end 0.7874 -0.4064)
			(stroke
				(width 0.1524)
				(type default)
			)
			(layer "F.SilkS")
		)
		(fp_line
			(start 0.67945 0.3048)
			(end 0.120396 0.3048)
			(stroke
				(width 0.1)
				(type default)
			)
			(layer "F.Fab")
		)
		(fp_line
			(start 0.67945 -0.3048)
			(end 0.67945 0.3048)
			(stroke
				(width 0.1)
				(type default)
			)
			(layer "F.Fab")
		)
		(fp_line
			(start 0.12065 -0.2794)
			(end 0.12065 -0.3048)
			(stroke
				(width 0.1)
				(type default)
			)
			(layer "F.Fab")
		)
		(fp_line
			(start 0.12065 -0.3048)
			(end 0.67945 -0.3048)
			(stroke
				(width 0.1)
				(type default)
			)
			(layer "F.Fab")
		)
		(fp_line
			(start 0.120396 0.3048)
			(end 0.120396 0.2794)
			(stroke
				(width 0.1)
				(type default)
			)
			(layer "F.Fab")
		)
		(fp_line
			(start 0.120396 0.2794)
			(end -0.12065 0.2794)
			(stroke
				(width 0.1)
				(type default)
			)
			(layer "F.Fab")
		)
		(fp_line
			(start -0.12065 0.3048)
			(end -0.67945 0.3048)
			(stroke
				(width 0.1)
				(type default)
			)
			(layer "F.Fab")
		)
		(fp_line
			(start -0.12065 0.2794)
			(end -0.12065 0.3048)
			(stroke
				(width 0.1)
				(type default)
			)
			(layer "F.Fab")
		)
		(fp_line
			(start -0.12065 -0.2794)
			(end 0.12065 -0.2794)
			(stroke
				(width 0.1)
				(type default)
			)
			(layer "F.Fab")
		)
		(fp_line
			(start -0.12065 -0.305054)
			(end -0.12065 -0.2794)
			(stroke
				(width 0.1)
				(type default)
			)
			(layer "F.Fab")
		)
		(fp_line
			(start -0.67945 0.3048)
			(end -0.67945 -0.305054)
			(stroke
				(width 0.1)
				(type default)
			)
			(layer "F.Fab")
		)
		(fp_line
			(start -0.67945 -0.305054)
			(end -0.12065 -0.305054)
			(stroke
				(width 0.1)
				(type default)
			)
			(layer "F.Fab")
		)
		(pad "1" smd circle
			(at -0.40005 0 180)
			(size 0 0)
			(layers "F.Cu" "F.Mask" "F.Paste")
			(net "BMC_CPLD_GPIO_7_R2")
		)
		(pad "2" smd circle
			(at 0.40005 0 180)
			(size 0 0)
			(layers "F.Cu" "F.Mask" "F.Paste")
			(net "BMC_CPLD_GPIO_7")
		)
	)
	(footprint ""
		(layer "F.Cu")
		(at 57.023 -76.3524 180)
		(property "Reference" "R182"
			(at 0 0 180)
			(layer "F.SilkS")
			(hide yes)
			(effects
				(font
					(size 1.27 1.27)
				)
			)
		)
		(property "Value" ""
			(at 0 0 180)
			(layer "F.Fab")
			(effects
				(font
					(size 1.27 1.27)
				)
			)
		)
		(duplicate_pad_numbers_are_jumpers no)
		(fp_line
			(start 0.7874 0.4064)
			(end -0.7874 0.4064)
			(stroke
				(width 0.1524)
				(type default)
			)
			(layer "F.SilkS")
		)
		(fp_line
			(start 0.7874 -0.4064)
			(end 0.7874 0.4064)
			(stroke
				(width 0.1524)
				(type default)
			)
			(layer "F.SilkS")
		)
		(fp_line
			(start -0.7874 0.4064)
			(end -0.7874 -0.4064)
			(stroke
				(width 0.1524)
				(type default)
			)
			(layer "F.SilkS")
		)
		(fp_line
			(start -0.7874 -0.4064)
			(end 0.7874 -0.4064)
			(stroke
				(width 0.1524)
				(type default)
			)
			(layer "F.SilkS")
		)
		(fp_line
			(start 0.67945 0.3048)
			(end 0.120396 0.3048)
			(stroke
				(width 0.1)
				(type default)
			)
			(layer "F.Fab")
		)
		(fp_line
			(start 0.67945 -0.3048)
			(end 0.67945 0.3048)
			(stroke
				(width 0.1)
				(type default)
			)
			(layer "F.Fab")
		)
		(fp_line
			(start 0.12065 -0.2794)
			(end 0.12065 -0.3048)
			(stroke
				(width 0.1)
				(type default)
			)
			(layer "F.Fab")
		)
		(fp_line
			(start 0.12065 -0.3048)
			(end 0.67945 -0.3048)
			(stroke
				(width 0.1)
				(type default)
			)
			(layer "F.Fab")
		)
		(fp_line
			(start 0.120396 0.3048)
			(end 0.120396 0.2794)
			(stroke
				(width 0.1)
				(type default)
			)
			(layer "F.Fab")
		)
		(fp_line
			(start 0.120396 0.2794)
			(end -0.12065 0.2794)
			(stroke
				(width 0.1)
				(type default)
			)
			(layer "F.Fab")
		)
		(fp_line
			(start -0.12065 0.3048)
			(end -0.67945 0.3048)
			(stroke
				(width 0.1)
				(type default)
			)
			(layer "F.Fab")
		)
		(fp_line
			(start -0.12065 0.2794)
			(end -0.12065 0.3048)
			(stroke
				(width 0.1)
				(type default)
			)
			(layer "F.Fab")
		)
		(fp_line
			(start -0.12065 -0.2794)
			(end 0.12065 -0.2794)
			(stroke
				(width 0.1)
				(type default)
			)
			(layer "F.Fab")
		)
		(fp_line
			(start -0.12065 -0.305054)
			(end -0.12065 -0.2794)
			(stroke
				(width 0.1)
				(type default)
			)
			(layer "F.Fab")
		)
		(fp_line
			(start -0.67945 0.3048)
			(end -0.67945 -0.305054)
			(stroke
				(width 0.1)
				(type default)
			)
			(layer "F.Fab")
		)
		(fp_line
			(start -0.67945 -0.305054)
			(end -0.12065 -0.305054)
			(stroke
				(width 0.1)
				(type default)
			)
			(layer "F.Fab")
		)
		(pad "1" smd circle
			(at -0.40005 0 180)
			(size 0 0)
			(layers "F.Cu" "F.Mask" "F.Paste")
			(net "GND")
		)
		(pad "2" smd circle
			(at 0.40005 0 180)
			(size 0 0)
			(layers "F.Cu" "F.Mask" "F.Paste")
			(net "FLASH_LATCH_D")
		)
	)
)
